# T6G (Grand Teton) — schematic netlist excerpt (pin names and nets, part order shuffled) for the footprints in the layout excerpt that follows; sources: Cadence DE-HDL packaged netlist, KiCad conversion of 04192023_DAF0TMB3IC0_F0TG_MB_C_brd_V02_OCP.brd

R983  Q_RES  4.7K 5% EMPTY  pkg 0201LF  page 276 : A = P1V8_CPU0_RT_1D ; B = TEST1_RT_CPU0_P0
C586  Q_CAP  22UF 4V 20% X6S  pkg C0402  page 279 : A = P0V9_CPU0_RT0_2A ; B = GND
R2422  Q_RES  33.2 1% CHIP  pkg 0402LF  page 150 : A = SMB_VR_SENSOR_3V3AUX_SDA ; B = SMB_VR_3V3AUX_SDA_R0

(kicad_pcb
	(version 20260206)
	(generator "pcbnew")
	(generator_version "10.0")
	(general
		(thickness 1.6)
		(legacy_teardrops no)
	)
	(paper "A4")
	(title_block
		(title "04192023_DAF0TMB3IC0_F0TG_MB_C_brd_V02_OCP.brd")
		(comment 1 "Grand Teton / footprints 6942-6944 of 8354")
	)
	(layers
		(0 "F.Cu" signal "TOP")
		(4 "In1.Cu" signal "GND")
		(6 "In2.Cu" signal "IN1")
		(8 "In3.Cu" signal "GND1")
		(10 "In4.Cu" signal "IN2")
		(12 "In5.Cu" signal "GND2")
		(14 "In6.Cu" signal "IN3")
		(16 "In7.Cu" signal "GND3")
		(18 "In8.Cu" signal "VCC")
		(20 "In9.Cu" signal "VCC1")
		(22 "In10.Cu" signal "GND4")
		(24 "In11.Cu" signal "IN4")
		(26 "In12.Cu" signal "GND5")
		(28 "In13.Cu" signal "IN5")
		(30 "In14.Cu" signal "GND6")
		(32 "In15.Cu" signal "IN6")
		(34 "In16.Cu" signal "GND7")
		(2 "B.Cu" signal "BOTTOM")
		(9 "F.Adhes" user "F.Adhesive")
		(11 "B.Adhes" user "B.Adhesive")
		(13 "F.Paste" user "Package Geometry/Pastemask Top")
		(15 "B.Paste" user "Package Geometry/Pastemask Bottom")
		(5 "F.SilkS" user "Ref Des/Silkscreen Top")
		(7 "B.SilkS" user "Ref Des/Silkscreen Bottom")
		(1 "F.Mask" user "Board Geometry/Soldermask Top")
		(3 "B.Mask" user "Board Geometry/Soldermask Bottom")
		(17 "Dwgs.User" user "User.Drawings")
		(19 "Cmts.User" user "User.Comments")
		(21 "Eco1.User" user "User.Eco1")
		(23 "Eco2.User" user "User.Eco2")
		(25 "Edge.Cuts" user "Board Geometry/Outline")
		(27 "Margin" user)
		(31 "F.CrtYd" user "Package Geometry/Place Bound Top")
		(29 "B.CrtYd" user "Package Geometry/Place Bound Bottom")
		(35 "F.Fab" user "Ref Des/Assembly Top")
		(33 "B.Fab" user "Ref Des/Assembly Bottom")
	)
	(footprint ""
		(layer "B.Cu")
		(at 175.886364 -10.1473 -90)
		(property "Reference" "R2422"
			(at 0 0 90)
			(layer "B.SilkS")
			(hide yes)
			(effects
				(font
					(size 1.27 1.27)
				)
				(justify mirror)
			)
		)
		(property "Value" ""
			(at 0 0 90)
			(layer "B.Fab")
			(effects
				(font
					(size 1.27 1.27)
				)
				(justify mirror)
			)
		)
		(duplicate_pad_numbers_are_jumpers no)
		(fp_line
			(start -0.7874 0.4064)
			(end 0.7874 0.4064)
			(stroke
				(width 0.1524)
				(type default)
			)
			(layer "B.SilkS")
		)
		(fp_line
			(start 0.7874 0.4064)
			(end 0.7874 -0.4064)
			(stroke
				(width 0.1524)
				(type default)
			)
			(layer "B.SilkS")
		)
		(fp_line
			(start -0.7874 -0.4064)
			(end -0.7874 0.4064)
			(stroke
				(width 0.1524)
				(type default)
			)
			(layer "B.SilkS")
		)
		(fp_line
			(start 0.7874 -0.4064)
			(end -0.7874 -0.4064)
			(stroke
				(width 0.1524)
				(type default)
			)
			(layer "B.SilkS")
		)
		(fp_line
			(start -0.67945 0.3048)
			(end -0.120396 0.3048)
			(stroke
				(width 0.1)
				(type default)
			)
			(layer "B.Fab")
		)
		(fp_line
			(start -0.120396 0.3048)
			(end -0.120396 0.2794)
			(stroke
				(width 0.1)
				(type default)
			)
			(layer "B.Fab")
		)
		(fp_line
			(start 0.12065 0.3048)
			(end 0.67945 0.3048)
			(stroke
				(width 0.1)
				(type default)
			)
			(layer "B.Fab")
		)
		(fp_line
			(start 0.67945 0.3048)
			(end 0.67945 -0.305054)
			(stroke
				(width 0.1)
				(type default)
			)
			(layer "B.Fab")
		)
		(fp_line
			(start -0.120396 0.2794)
			(end 0.12065 0.2794)
			(stroke
				(width 0.1)
				(type default)
			)
			(layer "B.Fab")
		)
		(fp_line
			(start 0.12065 0.2794)
			(end 0.12065 0.3048)
			(stroke
				(width 0.1)
				(type default)
			)
			(layer "B.Fab")
		)
		(fp_line
			(start -0.12065 -0.2794)
			(end -0.12065 -0.3048)
			(stroke
				(width 0.1)
				(type default)
			)
			(layer "B.Fab")
		)
		(fp_line
			(start 0.12065 -0.2794)
			(end -0.12065 -0.2794)
			(stroke
				(width 0.1)
				(type default)
			)
			(layer "B.Fab")
		)
		(fp_line
			(start -0.67945 -0.3048)
			(end -0.67945 0.3048)
			(stroke
				(width 0.1)
				(type default)
			)
			(layer "B.Fab")
		)
		(fp_line
			(start -0.12065 -0.3048)
			(end -0.67945 -0.3048)
			(stroke
				(width 0.1)
				(type default)
			)
			(layer "B.Fab")
		)
		(fp_line
			(start 0.12065 -0.305054)
			(end 0.12065 -0.2794)
			(stroke
				(width 0.1)
				(type default)
			)
			(layer "B.Fab")
		)
		(fp_line
			(start 0.67945 -0.305054)
			(end 0.12065 -0.305054)
			(stroke
				(width 0.1)
				(type default)
			)
			(layer "B.Fab")
		)
		(pad "1" smd circle
			(at 0.40005 0 90)
			(size 0 0)
			(layers "B.Cu" "B.Mask" "B.Paste")
			(net "SMB_VR_SENSOR_3V3AUX_SDA")
		)
		(pad "2" smd circle
			(at -0.40005 0 90)
			(size 0 0)
			(layers "B.Cu" "B.Mask" "B.Paste")
			(net "SMB_VR_3V3AUX_SDA_R0")
		)
	)
	(footprint ""
		(layer "B.Cu")
		(at 299.265594 -393.48156 180)
		(property "Reference" "R983"
			(at 0 0 0)
			(layer "B.SilkS")
			(hide yes)
			(effects
				(font
					(size 1.27 1.27)
				)
				(justify mirror)
			)
		)
		(property "Value" ""
			(at 0 0 0)
			(layer "B.Fab")
			(effects
				(font
					(size 1.27 1.27)
				)
				(justify mirror)
			)
		)
		(duplicate_pad_numbers_are_jumpers no)
		(fp_line
			(start 0.32512 0.175006)
			(end 0.32512 -0.175006)
			(stroke
				(width 0.1)
				(type default)
			)
			(layer "B.Fab")
		)
		(fp_line
			(start 0.32512 -0.175006)
			(end -0.32512 -0.175006)
			(stroke
				(width 0.1)
				(type default)
			)
			(layer "B.Fab")
		)
		(fp_line
			(start -0.32512 0.175006)
			(end 0.32512 0.175006)
			(stroke
				(width 0.1)
				(type default)
			)
			(layer "B.Fab")
		)
		(fp_line
			(start -0.32512 -0.175006)
			(end -0.32512 0.175006)
			(stroke
				(width 0.1)
				(type default)
			)
			(layer "B.Fab")
		)
		(pad "1" smd rect
			(at 0.2667 0)
			(size 0.3048 0.381)
			(layers "B.Cu" "B.Mask" "B.Paste")
			(net "P1V8_CPU0_RT_1D")
		)
		(pad "2" smd rect
			(at -0.2667 0 180)
			(size 0.3048 0.381)
			(layers "B.Cu" "B.Mask" "B.Paste")
			(net "TEST1_RT_CPU0_P0")
		)
	)
	(footprint ""
		(layer "B.Cu")
		(at 318.99098 -398.942052 90)
		(property "Reference" "C586"
			(at 0 0 90)
			(layer "B.SilkS")
			(hide yes)
			(effects
				(font
					(size 1.27 1.27)
				)
				(justify mirror)
			)
		)
		(property "Value" ""
			(at 0 0 90)
			(layer "B.Fab")
			(effects
				(font
					(size 1.27 1.27)
				)
				(justify mirror)
			)
		)
		(duplicate_pad_numbers_are_jumpers no)
		(fp_line
			(start 0.7874 -0.4064)
			(end -0.7874 -0.4064)
			(stroke
				(width 0.1524)
				(type default)
			)
			(layer "B.SilkS")
		)
		(fp_line
			(start -0.7874 -0.4064)
			(end -0.7874 0.4064)
			(stroke
				(width 0.1524)
				(type default)
			)
			(layer "B.SilkS")
		)
		(fp_line
			(start 0.7874 0.4064)
			(end 0.7874 -0.4064)
			(stroke
				(width 0.1524)
				(type default)
			)
			(layer "B.SilkS")
		)
		(fp_line
			(start -0.7874 0.4064)
			(end 0.7874 0.4064)
			(stroke
				(width 0.1524)
				(type default)
			)
			(layer "B.SilkS")
		)
		(fp_line
			(start 0.67945 -0.305054)
			(end 0.12065 -0.305054)
			(stroke
				(width 0.1)
				(type default)
			)
			(layer "B.Fab")
		)
		(fp_line
			(start 0.12065 -0.305054)
			(end 0.12065 -0.2794)
			(stroke
				(width 0.1)
				(type default)
			)
			(layer "B.Fab")
		)
		(fp_line
			(start -0.12065 -0.3048)
			(end -0.67945 -0.3048)
			(stroke
				(width 0.1)
				(type default)
			)
			(layer "B.Fab")
		)
		(fp_line
			(start -0.67945 -0.3048)
			(end -0.67945 0.3048)
			(stroke
				(width 0.1)
				(type default)
			)
			(layer "B.Fab")
		)
		(fp_line
			(start 0.12065 -0.2794)
			(end -0.12065 -0.2794)
			(stroke
				(width 0.1)
				(type default)
			)
			(layer "B.Fab")
		)
		(fp_line
			(start -0.12065 -0.2794)
			(end -0.12065 -0.3048)
			(stroke
				(width 0.1)
				(type default)
			)
			(layer "B.Fab")
		)
		(fp_line
			(start 0.12065 0.2794)
			(end 0.12065 0.3048)
			(stroke
				(width 0.1)
				(type default)
			)
			(layer "B.Fab")
		)
		(fp_line
			(start -0.120396 0.2794)
			(end 0.12065 0.2794)
			(stroke
				(width 0.1)
				(type default)
			)
			(layer "B.Fab")
		)
		(fp_line
			(start 0.67945 0.3048)
			(end 0.67945 -0.305054)
			(stroke
				(width 0.1)
				(type default)
			)
			(layer "B.Fab")
		)
		(fp_line
			(start 0.12065 0.3048)
			(end 0.67945 0.3048)
			(stroke
				(width 0.1)
				(type default)
			)
			(layer "B.Fab")
		)
		(fp_line
			(start -0.120396 0.3048)
			(end -0.120396 0.2794)
			(stroke
				(width 0.1)
				(type default)
			)
			(layer "B.Fab")
		)
		(fp_line
			(start -0.67945 0.3048)
			(end -0.120396 0.3048)
			(stroke
				(width 0.1)
				(type default)
			)
			(layer "B.Fab")
		)
		(pad "1" smd circle
			(at 0.40005 0 270)
			(size 0 0)
			(layers "B.Cu" "B.Mask" "B.Paste")
			(net "P0V9_CPU0_RT0_2A")
		)
		(pad "2" smd circle
			(at -0.40005 0 270)
			(size 0 0)
			(layers "B.Cu" "B.Mask" "B.Paste")
			(net "GND")
		)
	)
)
